# BASEBOARD_FAB2 (Tioga Pass) — schematic netlist excerpt (pin names and nets, part order shuffled) for the footprints in the layout excerpt that follows; sources: Cadence DE-HDL packaged netlist, KiCad conversion of Wiwynn_Tioga_Pass_MB.brd

U7E2  TTL1G08  NC7SZ08 IC  pkg SOTLF  page 95
  A(0)  = FM_PVCCIN_CPU0_PWR_IN_ALERT_N
  B(0)  = IRQ_PVCCIN_CPU0_VRHOT_LVC3_N
  Y(0)  = IRQ_CPU0_PROCHOT_G_N

C9U9  CAPP  470UF 2.5V 20% ALUM  pkg 3018  page 225 : A = PVDDQ_GHJ ; B = GND
R6T7  RES  150.0 1% CHIP  pkg 0402  page 112 : A = PVCCIO_CPU1 ; B = XDP_CPU1_TDO

(kicad_pcb
	(version 20260206)
	(generator "pcbnew")
	(generator_version "10.0")
	(general
		(thickness 1.6)
		(legacy_teardrops no)
	)
	(paper "A4")
	(title_block
		(title "Wiwynn_Tioga_Pass_MB.brd")
		(comment 1 "Tioga Pass / footprints 4097-4099 of 4770")
	)
	(layers
		(0 "F.Cu" signal "TOP")
		(4 "In1.Cu" signal "L2GND")
		(6 "In2.Cu" signal "L3")
		(8 "In3.Cu" signal "L4GND")
		(10 "In4.Cu" signal "L5")
		(12 "In5.Cu" signal "L6GND")
		(14 "In6.Cu" signal "L7VCC")
		(16 "In7.Cu" signal "L8VCC")
		(18 "In8.Cu" signal "L9GND")
		(20 "In9.Cu" signal "L10")
		(22 "In10.Cu" signal "L11GND")
		(24 "In11.Cu" signal "L12")
		(26 "In12.Cu" signal "L13GND")
		(2 "B.Cu" signal "BOTTOM")
		(9 "F.Adhes" user "F.Adhesive")
		(11 "B.Adhes" user "B.Adhesive")
		(13 "F.Paste" user "Package Geometry/Pastemask Top")
		(15 "B.Paste" user "Package Geometry/Pastemask Bottom")
		(5 "F.SilkS" user "Ref Des/Silkscreen Top")
		(7 "B.SilkS" user "Ref Des/Silkscreen Bottom")
		(1 "F.Mask" user "Board Geometry/Soldermask Top")
		(3 "B.Mask" user "Board Geometry/Soldermask Bottom")
		(17 "Dwgs.User" user "User.Drawings")
		(19 "Cmts.User" user "User.Comments")
		(21 "Eco1.User" user "User.Eco1")
		(23 "Eco2.User" user "User.Eco2")
		(25 "Edge.Cuts" user "Board Geometry/Outline")
		(27 "Margin" user)
		(31 "F.CrtYd" user "Package Geometry/Place Bound Top")
		(29 "B.CrtYd" user "Package Geometry/Place Bound Bottom")
		(35 "F.Fab" user "Ref Des/Assembly Top")
		(33 "B.Fab" user "Ref Des/Assembly Bottom")
	)
	(footprint ""
		(layer "B.Cu")
		(at 18.4404 -4.445)
		(property "Reference" "C9U9"
			(at -3.60807 0.254 270)
			(unlocked yes)
			(layer "B.SilkS")
			(effects
				(font
					(size 0.7874 0.5842)
					(thickness 0.1524)
				)
				(justify mirror)
			)
		)
		(property "Value" ""
			(at 0 0 0)
			(layer "B.Fab")
			(effects
				(font
					(size 1.27 1.27)
				)
				(justify mirror)
			)
		)
		(duplicate_pad_numbers_are_jumpers no)
		(fp_line
			(start -2.504948 -1.616456)
			(end -2.504948 1.633728)
			(stroke
				(width 0.1524)
				(type default)
			)
			(layer "B.SilkS")
		)
		(fp_line
			(start -2.504948 1.633728)
			(end -1.6002 1.633728)
			(stroke
				(width 0.1524)
				(type default)
			)
			(layer "B.SilkS")
		)
		(fp_line
			(start -2.286 7.366)
			(end -2.286 1.63195)
			(stroke
				(width 0.1524)
				(type default)
			)
			(layer "B.SilkS")
		)
		(fp_line
			(start -2.286 7.366)
			(end -1.600708 7.366)
			(stroke
				(width 0.1524)
				(type default)
			)
			(layer "B.SilkS")
		)
		(fp_line
			(start -1.6002 -1.616456)
			(end -2.504948 -1.616456)
			(stroke
				(width 0.1524)
				(type default)
			)
			(layer "B.SilkS")
		)
		(fp_line
			(start 1.6002 -1.616456)
			(end 2.563114 -1.616456)
			(stroke
				(width 0.1524)
				(type default)
			)
			(layer "B.SilkS")
		)
		(fp_line
			(start 2.286 7.366)
			(end 1.60147 7.366)
			(stroke
				(width 0.1524)
				(type default)
			)
			(layer "B.SilkS")
		)
		(fp_line
			(start 2.286 7.366)
			(end 2.286 1.632712)
			(stroke
				(width 0.1524)
				(type default)
			)
			(layer "B.SilkS")
		)
		(fp_line
			(start 2.563114 -1.616456)
			(end 2.563114 1.633728)
			(stroke
				(width 0.1524)
				(type default)
			)
			(layer "B.SilkS")
		)
		(fp_line
			(start 2.563114 1.633728)
			(end 1.6002 1.633728)
			(stroke
				(width 0.1524)
				(type default)
			)
			(layer "B.SilkS")
		)
		(fp_rect
			(start 2.286 -0.254)
			(end -2.286 7.366)
			(stroke
				(width 0)
				(type default)
			)
			(fill no)
			(layer "B.CrtYd")
		)
		(fp_line
			(start -2.286 -0.254)
			(end -2.286 7.366)
			(stroke
				(width 0.1)
				(type default)
			)
			(layer "B.Fab")
		)
		(fp_line
			(start -2.286 7.366)
			(end 2.286 7.366)
			(stroke
				(width 0.1)
				(type default)
			)
			(layer "B.Fab")
		)
		(fp_line
			(start 2.286 -0.254)
			(end -2.286 -0.254)
			(stroke
				(width 0.1)
				(type default)
			)
			(layer "B.Fab")
		)
		(fp_line
			(start 2.286 7.366)
			(end 2.286 -0.254)
			(stroke
				(width 0.1)
				(type default)
			)
			(layer "B.Fab")
		)
		(pad "1" smd rect
			(at 0 0 180)
			(size 2.54 3.048)
			(layers "B.Cu" "B.Mask" "B.Paste")
			(net "PVDDQ_GHJ")
		)
		(pad "2" smd rect
			(at 0 7.112 180)
			(size 2.54 3.048)
			(layers "B.Cu" "B.Mask" "B.Paste")
			(net "GND")
		)
	)
	(footprint ""
		(layer "B.Cu")
		(at 177.906426 -20.2057 90)
		(property "Reference" "R6T7"
			(at 0 0 90)
			(layer "B.SilkS")
			(hide yes)
			(effects
				(font
					(size 1.27 1.27)
				)
				(justify mirror)
			)
		)
		(property "Value" ""
			(at 0 0 90)
			(layer "B.Fab")
			(effects
				(font
					(size 1.27 1.27)
				)
				(justify mirror)
			)
		)
		(duplicate_pad_numbers_are_jumpers no)
		(fp_poly
			(pts
				(xy 0.2794 -0.1016) (xy -0.2794 -0.1016) (xy -0.2794 0.9906) (xy 0.2794 0.9906)
			)
			(stroke
				(width 0)
				(type default)
			)
			(fill no)
			(layer "B.CrtYd")
		)
		(fp_line
			(start 0.2794 -0.1016)
			(end 0.2794 0.9906)
			(stroke
				(width 0.1)
				(type default)
			)
			(layer "B.Fab")
		)
		(fp_line
			(start -0.2794 -0.1016)
			(end 0.2794 -0.1016)
			(stroke
				(width 0.1)
				(type default)
			)
			(layer "B.Fab")
		)
		(fp_line
			(start 0.2794 0.9906)
			(end -0.2794 0.9906)
			(stroke
				(width 0.1)
				(type default)
			)
			(layer "B.Fab")
		)
		(fp_line
			(start -0.2794 0.9906)
			(end -0.2794 -0.1016)
			(stroke
				(width 0.1)
				(type default)
			)
			(layer "B.Fab")
		)
		(pad "1" smd rect
			(at 0 0 270)
			(size 0.508 0.508)
			(layers "B.Cu" "B.Mask" "B.Paste")
			(net "PVCCIO_CPU1")
		)
		(pad "2" smd rect
			(at 0 0.889 270)
			(size 0.508 0.508)
			(layers "B.Cu" "B.Mask" "B.Paste")
			(net "XDP_CPU1_TDO")
		)
		(zone
			(layer "B.Cu")
			(hatch none 0.5)
			(connect_pads
				(clearance 0)
			)
			(min_thickness 0.25)
			(keepout
				(tracks allowed)
				(vias not_allowed)
				(pads allowed)
				(copperpour not_allowed)
				(footprints allowed)
			)
			(placement
				(enabled no)
				(sheetname "")
			)
			(fill
				(thermal_gap 0.5)
				(thermal_bridge_width 0.5)
				(island_removal_mode 0)
			)
			(polygon
				(pts
					(xy 178.160426 -20.4597) (xy 178.160426 -19.9517) (xy 178.541426 -19.9517) (xy 178.541426 -20.4597)
				)
			)
		)
		(zone
			(layer "B.Cu")
			(hatch none 0.5)
			(connect_pads
				(clearance 0)
			)
			(min_thickness 0.25)
			(keepout
				(tracks not_allowed)
				(vias allowed)
				(pads allowed)
				(copperpour not_allowed)
				(footprints allowed)
			)
			(placement
				(enabled no)
				(sheetname "")
			)
			(fill
				(thermal_gap 0.5)
				(thermal_bridge_width 0.5)
				(island_removal_mode 0)
			)
			(polygon
				(pts
					(xy 178.541426 -20.4597) (xy 178.541426 -19.9517) (xy 178.160426 -19.9517) (xy 178.160426 -20.4597)
				)
			)
		)
	)
	(footprint ""
		(layer "B.Cu")
		(at 370.929916 -37.08654 180)
		(property "Reference" "U7E2"
			(at -3.302 2.274316 0)
			(unlocked yes)
			(layer "B.SilkS")
			(effects
				(font
					(size 0.7874 0.5842)
					(thickness 0.1524)
				)
				(justify left mirror)
			)
		)
		(property "Value" ""
			(at 0 0 0)
			(layer "B.Fab")
			(effects
				(font
					(size 1.27 1.27)
				)
				(justify mirror)
			)
		)
		(duplicate_pad_numbers_are_jumpers no)
		(fp_circle
			(center 0.4699 -0.8382)
			(end 0.3429 -0.8382)
			(stroke
				(width 0.254)
				(type default)
			)
			(fill no)
			(layer "B.SilkS")
		)
		(fp_poly
			(pts
				(xy -0.21463 -0.450088) (xy -1.56337 -0.450088) (xy -1.56337 1.75006) (xy -0.21463 1.75006)
			)
			(stroke
				(width 0)
				(type default)
			)
			(fill no)
			(layer "B.CrtYd")
		)
		(fp_line
			(start -0.21463 1.75006)
			(end -0.21463 -0.450088)
			(stroke
				(width 0.1)
				(type default)
			)
			(layer "B.Fab")
		)
		(fp_line
			(start -0.21463 -0.450088)
			(end -1.56337 -0.450088)
			(stroke
				(width 0.1)
				(type default)
			)
			(layer "B.Fab")
		)
		(fp_line
			(start -1.56337 1.75006)
			(end -0.21463 1.75006)
			(stroke
				(width 0.1)
				(type default)
			)
			(layer "B.Fab")
		)
		(fp_line
			(start -1.56337 -0.450088)
			(end -1.56337 1.75006)
			(stroke
				(width 0.1)
				(type default)
			)
			(layer "B.Fab")
		)
		(fp_circle
			(center 0.4699 -0.8382)
			(end 0.3429 -0.8382)
			(stroke
				(width 0.254)
				(type default)
			)
			(fill no)
			(layer "B.Fab")
		)
		(pad "1" smd rect
			(at 0 0)
			(size 1.016 0.381)
			(layers "B.Cu" "B.Mask" "B.Paste")
			(net "FM_PVCCIN_CPU0_PWR_IN_ALERT_N")
		)
		(pad "2" smd rect
			(at 0 0.649986)
			(size 1.016 0.381)
			(layers "B.Cu" "B.Mask" "B.Paste")
			(net "IRQ_PVCCIN_CPU0_VRHOT_LVC3_N")
		)
		(pad "3" smd rect
			(at 0 1.299972)
			(size 1.016 0.381)
			(layers "B.Cu" "B.Mask" "B.Paste")
			(net "GND")
		)
		(pad "4" smd rect
			(at -1.778 1.299972)
			(size 1.016 0.381)
			(layers "B.Cu" "B.Mask" "B.Paste")
			(net "IRQ_CPU0_PROCHOT_G_N")
		)
		(pad "5" smd rect
			(at -1.778 0)
			(size 1.016 0.381)
			(layers "B.Cu" "B.Mask" "B.Paste")
			(net "P3V3_STBY")
		)
	)
)
